# BASEBOARD_FAB2 (Tioga Pass) — schematic netlist excerpt (pin names and nets, part order shuffled) for the footprints in the layout excerpt that follows; sources: Cadence DE-HDL packaged netlist, KiCad conversion of Wiwynn_Tioga_Pass_MB.brd

C2P11  CAP_A  0.1UF 16V 10% X7R  pkg 0402V  page 188 : A = P12V_STBY ; B = GND
R1U24  RES  2.7K 1% CHIP  pkg 0402  page 164 : A = P3V3_STBY ; B = FM_BOARD_SKU_ID2
C25W12  CAP_A  1.0UF 6.3V 10% X6S  pkg 0402V  page 151 : A = BMC_M_VREFCA ; B = GND

(kicad_pcb
	(version 20260206)
	(generator "pcbnew")
	(generator_version "10.0")
	(general
		(thickness 1.6)
		(legacy_teardrops no)
	)
	(paper "A4")
	(title_block
		(title "Wiwynn_Tioga_Pass_MB.brd")
		(comment 1 "Tioga Pass / footprints 4073-4075 of 4770")
	)
	(layers
		(0 "F.Cu" signal "TOP")
		(4 "In1.Cu" signal "L2GND")
		(6 "In2.Cu" signal "L3")
		(8 "In3.Cu" signal "L4GND")
		(10 "In4.Cu" signal "L5")
		(12 "In5.Cu" signal "L6GND")
		(14 "In6.Cu" signal "L7VCC")
		(16 "In7.Cu" signal "L8VCC")
		(18 "In8.Cu" signal "L9GND")
		(20 "In9.Cu" signal "L10")
		(22 "In10.Cu" signal "L11GND")
		(24 "In11.Cu" signal "L12")
		(26 "In12.Cu" signal "L13GND")
		(2 "B.Cu" signal "BOTTOM")
		(9 "F.Adhes" user "F.Adhesive")
		(11 "B.Adhes" user "B.Adhesive")
		(13 "F.Paste" user "Package Geometry/Pastemask Top")
		(15 "B.Paste" user "Package Geometry/Pastemask Bottom")
		(5 "F.SilkS" user "Ref Des/Silkscreen Top")
		(7 "B.SilkS" user "Ref Des/Silkscreen Bottom")
		(1 "F.Mask" user "Board Geometry/Soldermask Top")
		(3 "B.Mask" user "Board Geometry/Soldermask Bottom")
		(17 "Dwgs.User" user "User.Drawings")
		(19 "Cmts.User" user "User.Comments")
		(21 "Eco1.User" user "User.Eco1")
		(23 "Eco2.User" user "User.Eco2")
		(25 "Edge.Cuts" user "Board Geometry/Outline")
		(27 "Margin" user)
		(31 "F.CrtYd" user "Package Geometry/Place Bound Top")
		(29 "B.CrtYd" user "Package Geometry/Place Bound Bottom")
		(35 "F.Fab" user "Ref Des/Assembly Top")
		(33 "B.Fab" user "Ref Des/Assembly Bottom")
	)
	(footprint ""
		(layer "B.Cu")
		(at 431.2412 -22.5298 180)
		(property "Reference" "R1U24"
			(at 0 0 0)
			(layer "B.SilkS")
			(hide yes)
			(effects
				(font
					(size 1.27 1.27)
				)
				(justify mirror)
			)
		)
		(property "Value" ""
			(at 0 0 0)
			(layer "B.Fab")
			(effects
				(font
					(size 1.27 1.27)
				)
				(justify mirror)
			)
		)
		(duplicate_pad_numbers_are_jumpers no)
		(fp_poly
			(pts
				(xy 0.2794 -0.1016) (xy -0.2794 -0.1016) (xy -0.2794 0.9906) (xy 0.2794 0.9906)
			)
			(stroke
				(width 0)
				(type default)
			)
			(fill no)
			(layer "B.CrtYd")
		)
		(fp_line
			(start 0.2794 0.9906)
			(end -0.2794 0.9906)
			(stroke
				(width 0.1)
				(type default)
			)
			(layer "B.Fab")
		)
		(fp_line
			(start 0.2794 -0.1016)
			(end 0.2794 0.9906)
			(stroke
				(width 0.1)
				(type default)
			)
			(layer "B.Fab")
		)
		(fp_line
			(start -0.2794 0.9906)
			(end -0.2794 -0.1016)
			(stroke
				(width 0.1)
				(type default)
			)
			(layer "B.Fab")
		)
		(fp_line
			(start -0.2794 -0.1016)
			(end 0.2794 -0.1016)
			(stroke
				(width 0.1)
				(type default)
			)
			(layer "B.Fab")
		)
		(pad "1" smd rect
			(at 0 0)
			(size 0.508 0.508)
			(layers "B.Cu" "B.Mask" "B.Paste")
			(net "P3V3_STBY")
		)
		(pad "2" smd rect
			(at 0 0.889)
			(size 0.508 0.508)
			(layers "B.Cu" "B.Mask" "B.Paste")
			(net "FM_BOARD_SKU_ID2")
		)
		(zone
			(layer "B.Cu")
			(hatch none 0.5)
			(connect_pads
				(clearance 0)
			)
			(min_thickness 0.25)
			(keepout
				(tracks not_allowed)
				(vias allowed)
				(pads allowed)
				(copperpour not_allowed)
				(footprints allowed)
			)
			(placement
				(enabled no)
				(sheetname "")
			)
			(fill
				(thermal_gap 0.5)
				(thermal_bridge_width 0.5)
				(island_removal_mode 0)
			)
			(polygon
				(pts
					(xy 430.9872 -23.1648) (xy 431.4952 -23.1648) (xy 431.4952 -22.7838) (xy 430.9872 -22.7838)
				)
			)
		)
		(zone
			(layer "B.Cu")
			(hatch none 0.5)
			(connect_pads
				(clearance 0)
			)
			(min_thickness 0.25)
			(keepout
				(tracks allowed)
				(vias not_allowed)
				(pads allowed)
				(copperpour not_allowed)
				(footprints allowed)
			)
			(placement
				(enabled no)
				(sheetname "")
			)
			(fill
				(thermal_gap 0.5)
				(thermal_bridge_width 0.5)
				(island_removal_mode 0)
			)
			(polygon
				(pts
					(xy 430.9872 -22.7838) (xy 431.4952 -22.7838) (xy 431.4952 -23.1648) (xy 430.9872 -23.1648)
				)
			)
		)
	)
	(footprint ""
		(layer "B.Cu")
		(at 444.91275 -29.6164)
		(property "Reference" "C25W12"
			(at 0.8382 -0.67818 0)
			(unlocked yes)
			(layer "B.SilkS")
			(effects
				(font
					(size 0.4064 0.254)
					(thickness 0.1524)
				)
				(justify left mirror)
			)
		)
		(property "Value" ""
			(at 0 0 0)
			(layer "B.Fab")
			(effects
				(font
					(size 1.27 1.27)
				)
				(justify mirror)
			)
		)
		(duplicate_pad_numbers_are_jumpers no)
		(fp_poly
			(pts
				(xy -0.3048 -0.1016) (xy -0.3048 0.9906) (xy 0.3048 0.9906) (xy 0.3048 -0.1016)
			)
			(stroke
				(width 0)
				(type default)
			)
			(fill no)
			(layer "B.CrtYd")
		)
		(fp_line
			(start -0.3048 -0.1016)
			(end 0.3048 -0.1016)
			(stroke
				(width 0.1)
				(type default)
			)
			(layer "B.Fab")
		)
		(fp_line
			(start -0.3048 0.9906)
			(end -0.3048 -0.1016)
			(stroke
				(width 0.1)
				(type default)
			)
			(layer "B.Fab")
		)
		(fp_line
			(start 0.3048 -0.1016)
			(end 0.3048 0.9906)
			(stroke
				(width 0.1)
				(type default)
			)
			(layer "B.Fab")
		)
		(fp_line
			(start 0.3048 0.9906)
			(end -0.3048 0.9906)
			(stroke
				(width 0.1)
				(type default)
			)
			(layer "B.Fab")
		)
		(pad "1" smd rect
			(at 0 0 180)
			(size 0.508 0.508)
			(layers "B.Cu" "B.Mask" "B.Paste")
			(net "BMC_M_VREFCA")
		)
		(pad "2" smd rect
			(at 0 0.889 180)
			(size 0.508 0.508)
			(layers "B.Cu" "B.Mask" "B.Paste")
			(net "GND")
		)
		(zone
			(layer "B.Cu")
			(hatch none 0.5)
			(connect_pads
				(clearance 0)
			)
			(min_thickness 0.25)
			(keepout
				(tracks allowed)
				(vias not_allowed)
				(pads allowed)
				(copperpour not_allowed)
				(footprints allowed)
			)
			(placement
				(enabled no)
				(sheetname "")
			)
			(fill
				(thermal_gap 0.5)
				(thermal_bridge_width 0.5)
				(island_removal_mode 0)
			)
			(polygon
				(pts
					(xy 445.16675 -29.3624) (xy 444.65875 -29.3624) (xy 444.65875 -28.9814) (xy 445.16675 -28.9814)
				)
			)
		)
		(zone
			(layer "B.Cu")
			(hatch none 0.5)
			(connect_pads
				(clearance 0)
			)
			(min_thickness 0.25)
			(keepout
				(tracks not_allowed)
				(vias allowed)
				(pads allowed)
				(copperpour not_allowed)
				(footprints allowed)
			)
			(placement
				(enabled no)
				(sheetname "")
			)
			(fill
				(thermal_gap 0.5)
				(thermal_bridge_width 0.5)
				(island_removal_mode 0)
			)
			(polygon
				(pts
					(xy 445.16675 -28.9814) (xy 444.65875 -28.9814) (xy 444.65875 -29.3624) (xy 445.16675 -29.3624)
				)
			)
		)
	)
	(footprint ""
		(layer "B.Cu")
		(at 447.14668 -64.752982 180)
		(property "Reference" "C2P11"
			(at 0 0 0)
			(layer "B.SilkS")
			(hide yes)
			(effects
				(font
					(size 1.27 1.27)
				)
				(justify mirror)
			)
		)
		(property "Value" ""
			(at 0 0 0)
			(layer "B.Fab")
			(effects
				(font
					(size 1.27 1.27)
				)
				(justify mirror)
			)
		)
		(duplicate_pad_numbers_are_jumpers no)
		(fp_poly
			(pts
				(xy -0.3048 -0.1016) (xy -0.3048 0.9906) (xy 0.3048 0.9906) (xy 0.3048 -0.1016)
			)
			(stroke
				(width 0)
				(type default)
			)
			(fill no)
			(layer "B.CrtYd")
		)
		(fp_line
			(start 0.3048 0.9906)
			(end -0.3048 0.9906)
			(stroke
				(width 0.1)
				(type default)
			)
			(layer "B.Fab")
		)
		(fp_line
			(start 0.3048 -0.1016)
			(end 0.3048 0.9906)
			(stroke
				(width 0.1)
				(type default)
			)
			(layer "B.Fab")
		)
		(fp_line
			(start -0.3048 0.9906)
			(end -0.3048 -0.1016)
			(stroke
				(width 0.1)
				(type default)
			)
			(layer "B.Fab")
		)
		(fp_line
			(start -0.3048 -0.1016)
			(end 0.3048 -0.1016)
			(stroke
				(width 0.1)
				(type default)
			)
			(layer "B.Fab")
		)
		(pad "1" smd rect
			(at 0 0)
			(size 0.508 0.508)
			(layers "B.Cu" "B.Mask" "B.Paste")
			(net "P12V_STBY")
		)
		(pad "2" smd rect
			(at 0 0.889)
			(size 0.508 0.508)
			(layers "B.Cu" "B.Mask" "B.Paste")
			(net "GND")
		)
		(zone
			(layer "B.Cu")
			(hatch none 0.5)
			(connect_pads
				(clearance 0)
			)
			(min_thickness 0.25)
			(keepout
				(tracks not_allowed)
				(vias allowed)
				(pads allowed)
				(copperpour not_allowed)
				(footprints allowed)
			)
			(placement
				(enabled no)
				(sheetname "")
			)
			(fill
				(thermal_gap 0.5)
				(thermal_bridge_width 0.5)
				(island_removal_mode 0)
			)
			(polygon
				(pts
					(xy 446.89268 -65.387982) (xy 447.40068 -65.387982) (xy 447.40068 -65.006982) (xy 446.89268 -65.006982)
				)
			)
		)
		(zone
			(layer "B.Cu")
			(hatch none 0.5)
			(connect_pads
				(clearance 0)
			)
			(min_thickness 0.25)
			(keepout
				(tracks allowed)
				(vias not_allowed)
				(pads allowed)
				(copperpour not_allowed)
				(footprints allowed)
			)
			(placement
				(enabled no)
				(sheetname "")
			)
			(fill
				(thermal_gap 0.5)
				(thermal_bridge_width 0.5)
				(island_removal_mode 0)
			)
			(polygon
				(pts
					(xy 446.89268 -65.006982) (xy 447.40068 -65.006982) (xy 447.40068 -65.387982) (xy 446.89268 -65.387982)
				)
			)
		)
	)
)
